# S9S_MB_2U (Grand Teton) — schematic netlist excerpt (pin names and nets, part order shuffled) for the footprints in the layout excerpt that follows; sources: Cadence DE-HDL packaged netlist, KiCad conversion of 03242023_DA0F0TMBIJ0_F0T_Motherboard_J_brd_V01_OCP.brd

PR3824  Q_RES  4.53K 1% CHIP  pkg 0402LF  page 162 : A = P3V3_OCP_SENSE_2 ; B = GND
R4670  Q_RES  10K 1% EMPTY  pkg 0402LF  page 306 : A = A_HSC_HIGH ; B = GND

(kicad_pcb
	(version 20260206)
	(generator "pcbnew")
	(generator_version "10.0")
	(general
		(thickness 1.6)
		(legacy_teardrops no)
	)
	(paper "A4")
	(title_block
		(title "03242023_DA0F0TMBIJ0_F0T_Motherboard_J_brd_V01_OCP.brd")
		(comment 1 "Grand Teton / footprints 744-745 of 6105")
	)
	(layers
		(0 "F.Cu" signal "TOP")
		(4 "In1.Cu" signal "GND")
		(6 "In2.Cu" signal "IN1")
		(8 "In3.Cu" signal "GND1")
		(10 "In4.Cu" signal "IN2")
		(12 "In5.Cu" signal "GND2")
		(14 "In6.Cu" signal "IN3")
		(16 "In7.Cu" signal "GND3")
		(18 "In8.Cu" signal "VCC")
		(20 "In9.Cu" signal "VCC1")
		(22 "In10.Cu" signal "GND4")
		(24 "In11.Cu" signal "IN4")
		(26 "In12.Cu" signal "GND5")
		(28 "In13.Cu" signal "IN5")
		(30 "In14.Cu" signal "GND6")
		(32 "In15.Cu" signal "IN6")
		(34 "In16.Cu" signal "GND7")
		(2 "B.Cu" signal "BOTTOM")
		(9 "F.Adhes" user "F.Adhesive")
		(11 "B.Adhes" user "B.Adhesive")
		(13 "F.Paste" user "Package Geometry/Pastemask Top")
		(15 "B.Paste" user "Package Geometry/Pastemask Bottom")
		(5 "F.SilkS" user "Ref Des/Silkscreen Top")
		(7 "B.SilkS" user "Ref Des/Silkscreen Bottom")
		(1 "F.Mask" user "Board Geometry/Soldermask Top")
		(3 "B.Mask" user "Board Geometry/Soldermask Bottom")
		(17 "Dwgs.User" user "User.Drawings")
		(19 "Cmts.User" user "User.Comments")
		(21 "Eco1.User" user "User.Eco1")
		(23 "Eco2.User" user "User.Eco2")
		(25 "Edge.Cuts" user "Board Geometry/Outline")
		(27 "Margin" user)
		(31 "F.CrtYd" user "Package Geometry/Place Bound Top")
		(29 "B.CrtYd" user "Package Geometry/Place Bound Bottom")
		(35 "F.Fab" user "Ref Des/Assembly Top")
		(33 "B.Fab" user "Ref Des/Assembly Bottom")
	)
	(footprint ""
		(layer "F.Cu")
		(at 280.786078 -424.5483 90)
		(property "Reference" "R4670"
			(at 0 0 90)
			(layer "F.SilkS")
			(hide yes)
			(effects
				(font
					(size 1.27 1.27)
				)
			)
		)
		(property "Value" ""
			(at 0 0 90)
			(layer "F.Fab")
			(effects
				(font
					(size 1.27 1.27)
				)
			)
		)
		(duplicate_pad_numbers_are_jumpers no)
		(fp_line
			(start 0.7874 -0.4064)
			(end 0.7874 0.4064)
			(stroke
				(width 0.1524)
				(type default)
			)
			(layer "F.SilkS")
		)
		(fp_line
			(start -0.7874 -0.4064)
			(end 0.7874 -0.4064)
			(stroke
				(width 0.1524)
				(type default)
			)
			(layer "F.SilkS")
		)
		(fp_line
			(start 0.7874 0.4064)
			(end -0.7874 0.4064)
			(stroke
				(width 0.1524)
				(type default)
			)
			(layer "F.SilkS")
		)
		(fp_line
			(start -0.7874 0.4064)
			(end -0.7874 -0.4064)
			(stroke
				(width 0.1524)
				(type default)
			)
			(layer "F.SilkS")
		)
		(fp_line
			(start -0.12065 -0.305054)
			(end -0.12065 -0.2794)
			(stroke
				(width 0.1)
				(type default)
			)
			(layer "F.Fab")
		)
		(fp_line
			(start -0.67945 -0.305054)
			(end -0.12065 -0.305054)
			(stroke
				(width 0.1)
				(type default)
			)
			(layer "F.Fab")
		)
		(fp_line
			(start 0.67945 -0.3048)
			(end 0.67945 0.3048)
			(stroke
				(width 0.1)
				(type default)
			)
			(layer "F.Fab")
		)
		(fp_line
			(start 0.12065 -0.3048)
			(end 0.67945 -0.3048)
			(stroke
				(width 0.1)
				(type default)
			)
			(layer "F.Fab")
		)
		(fp_line
			(start 0.12065 -0.2794)
			(end 0.12065 -0.3048)
			(stroke
				(width 0.1)
				(type default)
			)
			(layer "F.Fab")
		)
		(fp_line
			(start -0.12065 -0.2794)
			(end 0.12065 -0.2794)
			(stroke
				(width 0.1)
				(type default)
			)
			(layer "F.Fab")
		)
		(fp_line
			(start 0.120396 0.2794)
			(end -0.12065 0.2794)
			(stroke
				(width 0.1)
				(type default)
			)
			(layer "F.Fab")
		)
		(fp_line
			(start -0.12065 0.2794)
			(end -0.12065 0.3048)
			(stroke
				(width 0.1)
				(type default)
			)
			(layer "F.Fab")
		)
		(fp_line
			(start 0.67945 0.3048)
			(end 0.120396 0.3048)
			(stroke
				(width 0.1)
				(type default)
			)
			(layer "F.Fab")
		)
		(fp_line
			(start 0.120396 0.3048)
			(end 0.120396 0.2794)
			(stroke
				(width 0.1)
				(type default)
			)
			(layer "F.Fab")
		)
		(fp_line
			(start -0.12065 0.3048)
			(end -0.67945 0.3048)
			(stroke
				(width 0.1)
				(type default)
			)
			(layer "F.Fab")
		)
		(fp_line
			(start -0.67945 0.3048)
			(end -0.67945 -0.305054)
			(stroke
				(width 0.1)
				(type default)
			)
			(layer "F.Fab")
		)
		(pad "1" smd circle
			(at -0.40005 0 90)
			(size 0 0)
			(layers "F.Cu" "F.Mask" "F.Paste")
			(net "A_HSC_HIGH")
		)
		(pad "2" smd circle
			(at 0.40005 0 90)
			(size 0 0)
			(layers "F.Cu" "F.Mask" "F.Paste")
			(net "GND")
		)
	)
	(footprint ""
		(layer "F.Cu")
		(at 84.44611 -59.242706 90)
		(property "Reference" "PR3824"
			(at 0 0 90)
			(layer "F.SilkS")
			(hide yes)
			(effects
				(font
					(size 1.27 1.27)
				)
			)
		)
		(property "Value" ""
			(at 0 0 90)
			(layer "F.Fab")
			(effects
				(font
					(size 1.27 1.27)
				)
			)
		)
		(duplicate_pad_numbers_are_jumpers no)
		(fp_line
			(start 0.7874 -0.4064)
			(end 0.7874 0.4064)
			(stroke
				(width 0.1524)
				(type default)
			)
			(layer "F.SilkS")
		)
		(fp_line
			(start -0.7874 -0.4064)
			(end 0.7874 -0.4064)
			(stroke
				(width 0.1524)
				(type default)
			)
			(layer "F.SilkS")
		)
		(fp_line
			(start 0.7874 0.4064)
			(end -0.7874 0.4064)
			(stroke
				(width 0.1524)
				(type default)
			)
			(layer "F.SilkS")
		)
		(fp_line
			(start -0.7874 0.4064)
			(end -0.7874 -0.4064)
			(stroke
				(width 0.1524)
				(type default)
			)
			(layer "F.SilkS")
		)
		(fp_line
			(start -0.12065 -0.305054)
			(end -0.12065 -0.2794)
			(stroke
				(width 0.1)
				(type default)
			)
			(layer "F.Fab")
		)
		(fp_line
			(start -0.67945 -0.305054)
			(end -0.12065 -0.305054)
			(stroke
				(width 0.1)
				(type default)
			)
			(layer "F.Fab")
		)
		(fp_line
			(start 0.67945 -0.3048)
			(end 0.67945 0.3048)
			(stroke
				(width 0.1)
				(type default)
			)
			(layer "F.Fab")
		)
		(fp_line
			(start 0.12065 -0.3048)
			(end 0.67945 -0.3048)
			(stroke
				(width 0.1)
				(type default)
			)
			(layer "F.Fab")
		)
		(fp_line
			(start 0.12065 -0.2794)
			(end 0.12065 -0.3048)
			(stroke
				(width 0.1)
				(type default)
			)
			(layer "F.Fab")
		)
		(fp_line
			(start -0.12065 -0.2794)
			(end 0.12065 -0.2794)
			(stroke
				(width 0.1)
				(type default)
			)
			(layer "F.Fab")
		)
		(fp_line
			(start 0.120396 0.2794)
			(end -0.12065 0.2794)
			(stroke
				(width 0.1)
				(type default)
			)
			(layer "F.Fab")
		)
		(fp_line
			(start -0.12065 0.2794)
			(end -0.12065 0.3048)
			(stroke
				(width 0.1)
				(type default)
			)
			(layer "F.Fab")
		)
		(fp_line
			(start 0.67945 0.3048)
			(end 0.120396 0.3048)
			(stroke
				(width 0.1)
				(type default)
			)
			(layer "F.Fab")
		)
		(fp_line
			(start 0.120396 0.3048)
			(end 0.120396 0.2794)
			(stroke
				(width 0.1)
				(type default)
			)
			(layer "F.Fab")
		)
		(fp_line
			(start -0.12065 0.3048)
			(end -0.67945 0.3048)
			(stroke
				(width 0.1)
				(type default)
			)
			(layer "F.Fab")
		)
		(fp_line
			(start -0.67945 0.3048)
			(end -0.67945 -0.305054)
			(stroke
				(width 0.1)
				(type default)
			)
			(layer "F.Fab")
		)
		(pad "1" smd circle
			(at -0.40005 0 90)
			(size 0 0)
			(layers "F.Cu" "F.Mask" "F.Paste")
			(net "P3V3_OCP_SENSE_2")
		)
		(pad "2" smd circle
			(at 0.40005 0 90)
			(size 0 0)
			(layers "F.Cu" "F.Mask" "F.Paste")
			(net "GND")
		)
	)
)
